# BASEBOARD_FAB2 (Tioga Pass) — schematic parts with pin connectivity, parts 2369–2369 of 4751; source: Cadence DE-HDL packaged netlist (pstxprt.dat, pstxnet.dat, pstchip.dat)

J4G2  SCONN288_H44441004  SCONN  pkg PIP  page 45
  1  \12v\(1)  = P12V_NVDIMM_ABC
  2  VSS(93)  GROUND  = GND
  3  DQ(4)  BI  = M_B_DQ<5>
  4  VSS(92)  GROUND  = GND
  5  DQ(0)  BI  = M_B_DQ<1>
  6  VSS(91)  GROUND  = GND
  7  DQS9P  BI  = M_B_DQS_DP<9>
  8  DQS9N  BI  = M_B_DQS_DN<9>
  9  VSS(90)  GROUND  = GND
  10  DQ(6)  BI  = M_B_DQ<7>
  11  VSS(89)  GROUND  = GND
  12  DQ(2)  BI  = M_B_DQ<3>
  13  VSS(88)  GROUND  = GND
  14  DQ(12)  BI  = M_B_DQ<13>
  15  VSS(87)  GROUND  = GND
  16  DQ(8)  BI  = M_B_DQ<9>
  17  VSS(86)  GROUND  = GND
  18  DQS10P  BI  = M_B_DQS_DP<10>
  19  DQS10N  BI  = M_B_DQS_DN<10>
  20  VSS(85)  GROUND  = GND
  21  DQ(14)  BI  = M_B_DQ<15>
  22  VSS(84)  GROUND  = GND
  23  DQ(10)  BI  = M_B_DQ<11>
  24  VSS(83)  GROUND  = GND
  25  DQ(20)  BI  = M_B_DQ<21>
  26  VSS(82)  GROUND  = GND
  27  DQ(16)  BI  = M_B_DQ<17>
  28  VSS(81)  GROUND  = GND
  29  DQS11P  BI  = M_B_DQS_DP<11>
  30  DQS11N  BI  = M_B_DQS_DN<11>
  31  VSS(80)  GROUND  = GND
  32  DQ(22)  BI  = M_B_DQ<23>
  33  VSS(79)  GROUND  = GND
  34  DQ(18)  BI  = M_B_DQ<19>
  35  VSS(78)  GROUND  = GND
  36  DQ(28)  BI  = M_B_DQ<29>
  37  VSS(77)  GROUND  = GND
  38  DQ(24)  BI  = M_B_DQ<25>
  39  VSS(76)  GROUND  = GND
  40  DQS12P  BI  = M_B_DQS_DP<12>
  41  DQS12N  BI  = M_B_DQS_DN<12>
  42  VSS(75)  GROUND  = GND
  43  DQ(30)  BI  = M_B_DQ<31>
  44  VSS(74)  GROUND  = GND
  45  DQ(26)  BI  = M_B_DQ<27>
  46  VSS(73)  GROUND  = GND
  47  CB(4)  BI  = M_B_ECC<5>
  48  VSS(72)  GROUND  = GND
  49  CB(0)  BI  = M_B_ECC<1>
  50  VSS(71)  GROUND  = GND
  51  DQS17P  BI  = M_B_DQS_DP<17>
  52  DQS17N  BI  = M_B_DQS_DN<17>
  53  VSS(70)  GROUND  = GND
  54  CB(6)  BI  = M_B_ECC<7>
  55  VSS(69)  GROUND  = GND
  56  CB(2)  BI  = M_B_ECC<3>
  57  VSS(68)  GROUND  = GND
  58  RESET_N  BI  = M_ABC_RST_N
  59  VDD(25)  POWER  = PVDDQ_ABC
  60  CKE(0)  BI  = M_B_CKE<0>
  61  VDD(24)  POWER  = PVDDQ_ABC
  62  ACT_N  BI  = M_B_ACT_N
  63  BG(0)  BI  = M_B_BG<0>
  64  VDD(23)  POWER  = PVDDQ_ABC
  65  A12  BI  = M_B_MA<12>
  66  A9  BI  = M_B_MA<9>
  67  VDD(22)  POWER  = PVDDQ_ABC
  68  A8  BI  = M_B_MA<8>
  69  A6  BI  = M_B_MA<6>
  70  VDD(21)  POWER  = PVDDQ_ABC
  71  A3  BI  = M_B_MA<3>
  72  A1  BI  = M_B_MA<1>
  73  VDD(20)  POWER  = PVDDQ_ABC
  74  CK0P  BI  = M_B_CLK_DP<0>
  75  CK0N  BI  = M_B_CLK_DN<0>
  76  VDD(19)  POWER  = PVDDQ_ABC
  77  VTT(1)  POWER  = PVTT_ABC
  78  EVENT_N  BI  = FM_DIMM_EVENT_COD_N
  79  A0  BI  = M_B_MA<0>
  80  VDD(18)  POWER  = PVDDQ_ABC
  81  BA(0)  BI  = M_B_BA<0>
  82  A16_RAS_N  BI  = M_B_MA<16>
  83  VDD(17)  POWER  = PVDDQ_ABC
  84  S0_N  BI  = M_B_CS_N<0>
  85  VDD(16)  POWER  = PVDDQ_ABC
  86  A15_CAS_N  BI  = M_B_MA<15>
  87  ODT(0)  BI  = M_B_ODT<0>
  88  VDD(15)  POWER  = PVDDQ_ABC
  89  S1_N  BI  = M_B_CS_N<1>
  90  VDD(14)  POWER  = PVDDQ_ABC
  91  ODT(1)  BI  = M_B_ODT<1>
  92  VDD(13)  POWER  = PVDDQ_ABC
  93  S2_N_C(0)  BI  = M_B_CS_N<2>
  94  VSS(67)  GROUND  = GND
  95  DQ(36)  BI  = M_B_DQ<37>
  96  VSS(66)  GROUND  = GND
  97  DQ(32)  BI  = M_B_DQ<33>
  98  VSS(65)  GROUND  = GND
  99  DQS13P  BI  = M_B_DQS_DP<13>
  100  DQS13N  BI  = M_B_DQS_DN<13>
  101  VSS(64)  GROUND  = GND
  102  DQ(38)  BI  = M_B_DQ<39>
  103  VSS(63)  GROUND  = GND
  104  DQ(34)  BI  = M_B_DQ<35>
  105  VSS(62)  GROUND  = GND
  106  DQ(44)  BI  = M_B_DQ<45>
  107  VSS(61)  GROUND  = GND
  108  DQ(40)  BI  = M_B_DQ<41>
  109  VSS(60)  GROUND  = GND
  110  DQS14P  BI  = M_B_DQS_DP<14>
  111  DQS14N  BI  = M_B_DQS_DN<14>
  112  VSS(59)  GROUND  = GND
  113  DQ(46)  BI  = M_B_DQ<47>
  114  VSS(58)  GROUND  = GND
  115  DQ(42)  BI  = M_B_DQ<43>
  116  VSS(57)  GROUND  = GND
  117  DQ(52)  BI  = M_B_DQ<53>
  118  VSS(56)  GROUND  = GND
  119  DQ(48)  BI  = M_B_DQ<49>
  120  VSS(55)  GROUND  = GND
  121  DQS15P  BI  = M_B_DQS_DP<15>
  122  DQS15N  BI  = M_B_DQS_DN<15>
  123  VSS(54)  GROUND  = GND
  124  DQ(54)  BI  = M_B_DQ<55>
  125  VSS(53)  GROUND  = GND
  126  DQ(50)  BI  = M_B_DQ<51>
  127  VSS(52)  GROUND  = GND
  128  DQ(60)  BI  = M_B_DQ<61>
  129  VSS(51)  GROUND  = GND
  130  DQ(56)  BI  = M_B_DQ<57>
  131  VSS(50)  GROUND  = GND
  132  DQS16P  BI  = M_B_DQS_DP<16>
  133  DQS16N  BI  = M_B_DQS_DN<16>
  134  VSS(49)  GROUND  = GND
  135  DQ(62)  BI  = M_B_DQ<63>
  136  VSS(48)  GROUND  = GND
  137  DQ(58)  BI  = M_B_DQ<59>
  138  VSS(47)  GROUND  = GND
  139  SA(0)  BI  = GND
  140  SA(1)  BI  = PVPP_ABC
  141  SCL  BI  = SMB_DDR_ABC_VPP_SCL
  142  VPP(4)  POWER  = PVPP_ABC
  143  VPP(3)  POWER  = PVPP_ABC
  144  RFU(2)  BI  = TP_CH_B_DIMM_B0_RFU_2
  145  \12v\(0)  = P12V_NVDIMM_ABC
  146  VREFCA  BI  = M_B_VREF
  147  VSS(46)  GROUND  = GND
  148  DQ(5)  BI  = M_B_DQ<4>
  149  VSS(45)  GROUND  = GND
  150  DQ(1)  BI  = M_B_DQ<0>
  151  VSS(44)  GROUND  = GND
  152  DQS0N  BI  = M_B_DQS_DN<0>
  153  DQS0P  BI  = M_B_DQS_DP<0>
  154  VSS(43)  GROUND  = GND
  155  DQ(7)  BI  = M_B_DQ<6>
  156  VSS(42)  GROUND  = GND
  157  DQ(3)  BI  = M_B_DQ<2>
  158  VSS(41)  GROUND  = GND
  159  DQ(13)  BI  = M_B_DQ<12>
  160  VSS(40)  GROUND  = GND
  161  DQ(9)  BI  = M_B_DQ<8>
  162  VSS(39)  GROUND  = GND
  163  DQS1N  BI  = M_B_DQS_DN<1>
  164  DQS1P  BI  = M_B_DQS_DP<1>
  165  VSS(38)  GROUND  = GND
  166  DQ(15)  BI  = M_B_DQ<14>
  167  VSS(37)  GROUND  = GND
  168  DQ(11)  BI  = M_B_DQ<10>
  169  VSS(36)  GROUND  = GND
  170  DQ(21)  BI  = M_B_DQ<20>
  171  VSS(35)  GROUND  = GND
  172  DQ(17)  BI  = M_B_DQ<16>
  173  VSS(34)  GROUND  = GND
  174  DQS2N  BI  = M_B_DQS_DN<2>
  175  DQS2P  BI  = M_B_DQS_DP<2>
  176  VSS(33)  GROUND  = GND
  177  DQ(23)  BI  = M_B_DQ<22>
  178  VSS(32)  GROUND  = GND
  179  DQ(19)  BI  = M_B_DQ<18>
  180  VSS(31)  GROUND  = GND
  181  DQ(29)  BI  = M_B_DQ<28>
  182  VSS(30)  GROUND  = GND
  183  DQ(25)  BI  = M_B_DQ<24>
  184  VSS(29)  GROUND  = GND
  185  DQS3N  BI  = M_B_DQS_DN<3>
  186  DQS3P  BI  = M_B_DQS_DP<3>
  187  VSS(28)  GROUND  = GND
  188  DQ(31)  BI  = M_B_DQ<30>
  189  VSS(27)  GROUND  = GND
  190  DQ(27)  BI  = M_B_DQ<26>
  191  VSS(26)  GROUND  = GND
  192  CB(5)  BI  = M_B_ECC<4>
  193  VSS(25)  GROUND  = GND
  194  CB(1)  BI  = M_B_ECC<0>
  195  VSS(24)  GROUND  = GND
  196  DQS8N  BI  = M_B_DQS_DN<8>
  197  DQS8P  BI  = M_B_DQS_DP<8>
  198  VSS(23)  GROUND  = GND
  199  CB(7)  BI  = M_B_ECC<6>
  200  VSS(22)  GROUND  = GND
  201  CB(3)  BI  = M_B_ECC<2>
  202  VSS(21)  GROUND  = GND
  203  CKE(1)  BI  = M_B_CKE<1>
  204  VDD(12)  POWER  = PVDDQ_ABC
  205  RFU(0)  BI  = TP_CH_B_DIMM_B0_RFU_0
  206  VDD(11)  POWER  = PVDDQ_ABC
  207  BG(1)  BI  = M_B_BG<1>
  208  ALERT_N  BI  = M_B_ALERT_N
  209  VDD(10)  POWER  = PVDDQ_ABC
  210  A11  BI  = M_B_MA<11>
  211  A7  BI  = M_B_MA<7>
  212  VDD(9)  POWER  = PVDDQ_ABC
  213  A5  BI  = M_B_MA<5>
  214  A4  BI  = M_B_MA<4>
  215  VDD(8)  POWER  = PVDDQ_ABC
  216  A2  BI  = M_B_MA<2>
  217  VDD(7)  POWER  = PVDDQ_ABC
  218  CK1P  BI  = M_B_CLK_DP<1>
  219  CK1N  BI  = M_B_CLK_DN<1>
  220  VDD(6)  POWER  = PVDDQ_ABC
  221  VTT(0)  POWER  = PVTT_ABC
  222  PAR  BI  = M_B_PAR
  223  VDD(5)  POWER  = PVDDQ_ABC
  224  BA(1)  BI  = M_B_BA<1>
  225  A10  BI  = M_B_MA<10>
  226  VDD(4)  POWER  = PVDDQ_ABC
  227  RFU(1)  BI  = TP_CH_B_DIMM_B0_RFU_1
  228  A14_WE_N  BI  = M_B_MA<14>
  229  VDD(3)  POWER  = PVDDQ_ABC
  230  SAVE_N_NC  BI  = FM_ADR_COMPLETE_ABC_N
  231  VDD(2)  POWER  = PVDDQ_ABC
  232  A13  BI  = M_B_MA<13>
  233  VDD(1)  POWER  = PVDDQ_ABC
  234  A17  BI  = M_B_MA<17>
  235  C(2)  BI  = M_B_C<2>
  236  VDD(0)  POWER  = PVDDQ_ABC
  237  S3_N_C(1)  BI  = M_B_CS_N<3>
  238  SA(2)  BI  = GND
  239  VSS(20)  GROUND  = GND
  240  DQ(37)  BI  = M_B_DQ<36>
  241  VSS(19)  GROUND  = GND
  242  DQ(33)  BI  = M_B_DQ<32>
  243  VSS(18)  GROUND  = GND
  244  DQS4N  BI  = M_B_DQS_DN<4>
  245  DQS4P  BI  = M_B_DQS_DP<4>
  246  VSS(17)  GROUND  = GND
  247  DQ(39)  BI  = M_B_DQ<38>
  248  VSS(16)  GROUND  = GND
  249  DQ(35)  BI  = M_B_DQ<34>
  250  VSS(15)  GROUND  = GND
  251  DQ(45)  BI  = M_B_DQ<44>
  252  VSS(14)  GROUND  = GND
  253  DQ(41)  BI  = M_B_DQ<40>
  254  VSS(13)  GROUND  = GND
  255  DQS5N  BI  = M_B_DQS_DN<5>
  256  DQS5P  BI  = M_B_DQS_DP<5>
  257  VSS(12)  GROUND  = GND
  258  DQ(47)  BI  = M_B_DQ<46>
  259  VSS(11)  GROUND  = GND
  260  DQ(43)  BI  = M_B_DQ<42>
  261  VSS(10)  GROUND  = GND
  262  DQ(53)  BI  = M_B_DQ<52>
  263  VSS(9)  GROUND  = GND
  264  DQ(49)  BI  = M_B_DQ<48>
  265  VSS(8)  GROUND  = GND
  266  DQS6N  BI  = M_B_DQS_DN<6>
  267  DQS6P  BI  = M_B_DQS_DP<6>
  268  VSS(7)  GROUND  = GND
  269  DQ(55)  BI  = M_B_DQ<54>
  270  VSS(6)  GROUND  = GND
  271  DQ(51)  BI  = M_B_DQ<50>
  272  VSS(5)  GROUND  = GND
  273  DQ(61)  BI  = M_B_DQ<60>
  274  VSS(4)  GROUND  = GND
  275  DQ(57)  BI  = M_B_DQ<56>
  276  VSS(3)  GROUND  = GND
  277  DQS7N  BI  = M_B_DQS_DN<7>
  278  DQS7P  BI  = M_B_DQS_DP<7>
  279  VSS(2)  GROUND  = GND
  280  DQ(63)  BI  = M_B_DQ<62>
  281  VSS(1)  GROUND  = GND
  282  DQ(59)  BI  = M_B_DQ<58>
  283  VSS(0)  GROUND  = GND
  284  VDDSPD  BI  = PVPP_ABC
  285  SDA  BI  = SMB_DDR_ABC_VPP_SDA
  286  VPP(1)  POWER  = PVPP_ABC
  287  VPP(0)  POWER  = PVPP_ABC
  288  VPP(2)  POWER  = PVPP_ABC
